(kicad_pcb
	(version 20260206)
	(generator "pcbnew")
	(generator_version "10.0")
	(general
		(thickness 1.6)
		(legacy_teardrops no)
	)
	(paper "A4")
	(title_block
		(title "v1-chassis-manager — T6M_CM_d_v01_1031_1645.brd")
		(comment 1 "Open CloudServer (Microsoft) / footprints 864-873 of 2512")
	)
	(layers
		(0 "F.Cu" signal "TOP")
		(4 "In1.Cu" signal "GND1")
		(6 "In2.Cu" signal "IN1")
		(8 "In3.Cu" signal "VCC1")
		(10 "In4.Cu" signal "VCC2")
		(12 "In5.Cu" signal "GND2")
		(14 "In6.Cu" signal "IN2")
		(16 "In7.Cu" signal "IN3")
		(18 "In8.Cu" signal "GND3")
		(2 "B.Cu" signal "BOTTOM")
		(9 "F.Adhes" user "F.Adhesive")
		(11 "B.Adhes" user "B.Adhesive")
		(13 "F.Paste" user "Package Geometry/Pastemask Top")
		(15 "B.Paste" user "Package Geometry/Pastemask Bottom")
		(5 "F.SilkS" user "Ref Des/Silkscreen Top")
		(7 "B.SilkS" user "Ref Des/Silkscreen Bottom")
		(1 "F.Mask" user "Board Geometry/Soldermask Top")
		(3 "B.Mask" user "Board Geometry/Soldermask Bottom")
		(17 "Dwgs.User" user "User.Drawings")
		(19 "Cmts.User" user "User.Comments")
		(21 "Eco1.User" user "User.Eco1")
		(23 "Eco2.User" user "User.Eco2")
		(25 "Edge.Cuts" user "Board Geometry/Outline")
		(27 "Margin" user)
		(31 "F.CrtYd" user "Package Geometry/Place Bound Top")
		(29 "B.CrtYd" user "Package Geometry/Place Bound Bottom")
		(35 "F.Fab" user "Ref Des/Assembly Top")
		(33 "B.Fab" user "Ref Des/Assembly Bottom")
	)
	(footprint ""
		(layer "F.Cu")
		(at 137.593578 -61.720222 180)
		(property "Reference" "R509"
			(at 0.802894 -4.848098 0)
			(unlocked yes)
			(layer "F.SilkS")
			(effects
				(font
					(size 0.7874 0.5842)
					(thickness 0.1524)
				)
				(justify left)
			)
		)
		(property "Value" ""
			(at 0 0 180)
			(layer "F.Fab")
			(effects
				(font
					(size 1.27 1.27)
				)
			)
		)
		(duplicate_pad_numbers_are_jumpers no)
		(fp_line
			(start 0.7874 0.4064)
			(end -0.7874 0.4064)
			(stroke
				(width 0.1524)
				(type default)
			)
			(layer "F.SilkS")
		)
		(fp_line
			(start 0.7874 -0.4064)
			(end 0.7874 0.4064)
			(stroke
				(width 0.1524)
				(type default)
			)
			(layer "F.SilkS")
		)
		(fp_line
			(start -0.7874 0.4064)
			(end -0.7874 -0.4064)
			(stroke
				(width 0.1524)
				(type default)
			)
			(layer "F.SilkS")
		)
		(fp_line
			(start -0.7874 -0.4064)
			(end 0.7874 -0.4064)
			(stroke
				(width 0.1524)
				(type default)
			)
			(layer "F.SilkS")
		)
		(fp_poly
			(pts
				(xy -0.508 0.2794) (xy -0.508 0.2286) (xy -0.635 0.2286) (xy -0.635 -0.254) (xy -0.5334 -0.254)
				(xy -0.5334 -0.2794) (xy 0.5334 -0.2794) (xy 0.5334 -0.254) (xy 0.635 -0.254) (xy 0.635 0.254) (xy 0.5334 0.254)
				(xy 0.5334 0.2794)
			)
			(stroke
				(width 0)
				(type default)
			)
			(fill no)
			(layer "F.CrtYd")
		)
		(pad "1" smd rect
			(at 0.40005 0 180)
			(size 0.4572 0.508)
			(layers "F.Cu" "F.Mask" "F.Paste")
			(net "P3V3_NODE1")
		)
		(pad "2" smd rect
			(at -0.40005 0 180)
			(size 0.4572 0.508)
			(layers "F.Cu" "F.Mask" "F.Paste")
			(net "SATA_NODE1_GPIO1")
		)
	)
	(footprint ""
		(layer "F.Cu")
		(at 122.846592 -154.541728 180)
		(property "Reference" "U117"
			(at 58.090562 -110.992412 0)
			(unlocked yes)
			(layer "F.SilkS")
			(effects
				(font
					(size 0.7874 0.5842)
					(thickness 0.1524)
				)
			)
		)
		(property "Value" ""
			(at 0 0 180)
			(layer "F.Fab")
			(effects
				(font
					(size 1.27 1.27)
				)
			)
		)
		(duplicate_pad_numbers_are_jumpers no)
		(fp_line
			(start 1.651 1.905)
			(end -1.651 1.905)
			(stroke
				(width 0.1524)
				(type default)
			)
			(layer "F.SilkS")
		)
		(fp_line
			(start 1.651 -1.905)
			(end 1.651 1.905)
			(stroke
				(width 0.1524)
				(type default)
			)
			(layer "F.SilkS")
		)
		(fp_line
			(start -1.651 1.905)
			(end -1.651 -1.905)
			(stroke
				(width 0.1524)
				(type default)
			)
			(layer "F.SilkS")
		)
		(fp_line
			(start -1.651 -1.905)
			(end 1.651 -1.905)
			(stroke
				(width 0.1524)
				(type default)
			)
			(layer "F.SilkS")
		)
		(fp_poly
			(pts
				(xy -1.524 0.7112) (xy -1.524 1.7526) (xy -0.508 1.7526) (xy -0.508 0.6985) (xy 0.508 0.6985) (xy 0.508 1.7526)
				(xy 1.524 1.7526) (xy 1.524 0.6985) (xy 1.524 -0.6985) (xy 0.508 -0.6985) (xy 0.508 -1.7526) (xy -0.508 -1.7526)
				(xy -0.508 -0.6985) (xy -1.524 -0.6985) (xy -1.524 0.6985)
			)
			(stroke
				(width 0)
				(type default)
			)
			(fill no)
			(layer "F.CrtYd")
		)
		(fp_text user "S"
			(at 2.198878 1.18237 0)
			(unlocked yes)
			(layer "F.SilkS")
			(effects
				(font
					(size 0.635 0.4064)
					(thickness 0.1524)
				)
			)
		)
		(fp_text user "D"
			(at -2.035048 -1.44272 0)
			(unlocked yes)
			(layer "F.SilkS")
			(effects
				(font
					(size 0.635 0.4064)
					(thickness 0.1524)
				)
			)
		)
		(fp_text user "G"
			(at -2.224532 1.277366 0)
			(unlocked yes)
			(layer "F.SilkS")
			(effects
				(font
					(size 0.635 0.4064)
					(thickness 0.1524)
				)
			)
		)
		(pad "D" smd rect
			(at 0 -1.1176 180)
			(size 1.016 1.27)
			(layers "F.Cu" "F.Mask" "F.Paste")
			(net "I2C_PSU1_SDA")
		)
		(pad "G" smd rect
			(at -1.016 1.1176 180)
			(size 1.016 1.27)
			(layers "F.Cu" "F.Mask" "F.Paste")
			(net "PMBUS1_EN")
		)
		(pad "S" smd rect
			(at 1.016 1.1176 180)
			(size 1.016 1.27)
			(layers "F.Cu" "F.Mask" "F.Paste")
			(net "I2C_PSU1_SDA_MOS")
		)
	)
	(footprint ""
		(layer "F.Cu")
		(at 181.45633 -130.412236)
		(property "Reference" "R1046"
			(at 11.790426 0.416814 0)
			(unlocked yes)
			(layer "F.SilkS")
			(effects
				(font
					(size 0.7874 0.5842)
					(thickness 0.1524)
				)
				(justify left)
			)
		)
		(property "Value" ""
			(at 0 0 0)
			(layer "F.Fab")
			(effects
				(font
					(size 1.27 1.27)
				)
			)
		)
		(duplicate_pad_numbers_are_jumpers no)
		(fp_line
			(start -0.7874 -0.4064)
			(end 0.7874 -0.4064)
			(stroke
				(width 0.1524)
				(type default)
			)
			(layer "F.SilkS")
		)
		(fp_line
			(start -0.7874 0.4064)
			(end -0.7874 -0.4064)
			(stroke
				(width 0.1524)
				(type default)
			)
			(layer "F.SilkS")
		)
		(fp_line
			(start 0.7874 -0.4064)
			(end 0.7874 0.4064)
			(stroke
				(width 0.1524)
				(type default)
			)
			(layer "F.SilkS")
		)
		(fp_line
			(start 0.7874 0.4064)
			(end -0.7874 0.4064)
			(stroke
				(width 0.1524)
				(type default)
			)
			(layer "F.SilkS")
		)
		(fp_poly
			(pts
				(xy -0.508 0.2794) (xy -0.508 0.2286) (xy -0.635 0.2286) (xy -0.635 -0.254) (xy -0.5334 -0.254)
				(xy -0.5334 -0.2794) (xy 0.5334 -0.2794) (xy 0.5334 -0.254) (xy 0.635 -0.254) (xy 0.635 0.254) (xy 0.5334 0.254)
				(xy 0.5334 0.2794)
			)
			(stroke
				(width 0)
				(type default)
			)
			(fill no)
			(layer "F.CrtYd")
		)
		(pad "1" smd rect
			(at 0.40005 0)
			(size 0.4572 0.508)
			(layers "F.Cu" "F.Mask" "F.Paste")
			(net "FM_NODE1_CORE0_1_RST_L")
		)
		(pad "2" smd rect
			(at -0.40005 0)
			(size 0.4572 0.508)
			(layers "F.Cu" "F.Mask" "F.Paste")
			(net "P3V3_STB_NODE1")
		)
	)
	(footprint ""
		(layer "F.Cu")
		(at 11.24458 -154.13736 -90)
		(property "Reference" "C551"
			(at 5.109464 -8.015732 90)
			(unlocked yes)
			(layer "F.SilkS")
			(effects
				(font
					(size 0.7874 0.5842)
					(thickness 0.1524)
				)
				(justify left)
			)
		)
		(property "Value" ""
			(at 0 0 270)
			(layer "F.Fab")
			(effects
				(font
					(size 1.27 1.27)
				)
			)
		)
		(duplicate_pad_numbers_are_jumpers no)
		(fp_line
			(start -0.7874 0.4064)
			(end -0.7874 -0.4064)
			(stroke
				(width 0.1524)
				(type default)
			)
			(layer "F.SilkS")
		)
		(fp_line
			(start 0.7874 0.4064)
			(end -0.7874 0.4064)
			(stroke
				(width 0.1524)
				(type default)
			)
			(layer "F.SilkS")
		)
		(fp_line
			(start 0 0.381)
			(end 0 -0.381)
			(stroke
				(width 0.1524)
				(type default)
			)
			(layer "F.SilkS")
		)
		(fp_line
			(start -0.7874 -0.4064)
			(end 0.7874 -0.4064)
			(stroke
				(width 0.1524)
				(type default)
			)
			(layer "F.SilkS")
		)
		(fp_line
			(start 0.7874 -0.4064)
			(end 0.7874 0.4064)
			(stroke
				(width 0.1524)
				(type default)
			)
			(layer "F.SilkS")
		)
		(fp_poly
			(pts
				(xy -0.5334 0.254) (xy -0.635 0.254) (xy -0.635 0.2286) (xy -0.635 -0.254) (xy -0.5334 -0.254) (xy -0.5334 -0.2794)
				(xy 0.5334 -0.2794) (xy 0.5334 -0.254) (xy 0.635 -0.254) (xy 0.635 0.254) (xy 0.5334 0.254) (xy 0.5334 0.2794)
				(xy -0.508 0.2794) (xy -0.5334 0.2794)
			)
			(stroke
				(width 0)
				(type default)
			)
			(fill no)
			(layer "F.CrtYd")
		)
		(pad "1" smd rect
			(at 0.40005 0 270)
			(size 0.4572 0.508)
			(layers "F.Cu" "F.Mask" "F.Paste")
			(net "GND")
		)
		(pad "2" smd rect
			(at -0.40005 0 270)
			(size 0.4572 0.508)
			(layers "F.Cu" "F.Mask" "F.Paste")
			(net "N54258535")
		)
	)
	(footprint ""
		(layer "F.Cu")
		(at 90.81262 -168.434512 180)
		(property "Reference" "R918"
			(at -85.97392 -72.627744 0)
			(unlocked yes)
			(layer "F.SilkS")
			(effects
				(font
					(size 0.7874 0.5842)
					(thickness 0.1524)
				)
				(justify left)
			)
		)
		(property "Value" ""
			(at 0 0 180)
			(layer "F.Fab")
			(effects
				(font
					(size 1.27 1.27)
				)
			)
		)
		(duplicate_pad_numbers_are_jumpers no)
		(fp_line
			(start 0.7874 0.4064)
			(end -0.7874 0.4064)
			(stroke
				(width 0.1524)
				(type default)
			)
			(layer "F.SilkS")
		)
		(fp_line
			(start 0.7874 -0.4064)
			(end 0.7874 0.4064)
			(stroke
				(width 0.1524)
				(type default)
			)
			(layer "F.SilkS")
		)
		(fp_line
			(start -0.7874 0.4064)
			(end -0.7874 -0.4064)
			(stroke
				(width 0.1524)
				(type default)
			)
			(layer "F.SilkS")
		)
		(fp_line
			(start -0.7874 -0.4064)
			(end 0.7874 -0.4064)
			(stroke
				(width 0.1524)
				(type default)
			)
			(layer "F.SilkS")
		)
		(fp_poly
			(pts
				(xy -0.508 0.2794) (xy -0.508 0.2286) (xy -0.635 0.2286) (xy -0.635 -0.254) (xy -0.5334 -0.254)
				(xy -0.5334 -0.2794) (xy 0.5334 -0.2794) (xy 0.5334 -0.254) (xy 0.635 -0.254) (xy 0.635 0.254) (xy 0.5334 0.254)
				(xy 0.5334 0.2794)
			)
			(stroke
				(width 0)
				(type default)
			)
			(fill no)
			(layer "F.CrtYd")
		)
		(pad "1" smd rect
			(at 0.40005 0 180)
			(size 0.4572 0.508)
			(layers "F.Cu" "F.Mask" "F.Paste")
			(net "UART_T5_NODE2_TXD")
		)
		(pad "2" smd rect
			(at -0.40005 0 180)
			(size 0.4572 0.508)
			(layers "F.Cu" "F.Mask" "F.Paste")
			(net "UART_T5_NODE2_TXD_R")
		)
	)
	(footprint ""
		(layer "F.Cu")
		(at 34.360358 -130.506216 180)
		(property "Reference" "C832"
			(at 2.386076 1.076706 0)
			(unlocked yes)
			(layer "F.SilkS")
			(effects
				(font
					(size 0.7874 0.5842)
					(thickness 0.1524)
				)
				(justify left)
			)
		)
		(property "Value" ""
			(at 0 0 180)
			(layer "F.Fab")
			(effects
				(font
					(size 1.27 1.27)
				)
			)
		)
		(duplicate_pad_numbers_are_jumpers no)
		(fp_line
			(start 0.7874 0.4064)
			(end -0.7874 0.4064)
			(stroke
				(width 0.1524)
				(type default)
			)
			(layer "F.SilkS")
		)
		(fp_line
			(start 0.7874 -0.4064)
			(end 0.7874 0.4064)
			(stroke
				(width 0.1524)
				(type default)
			)
			(layer "F.SilkS")
		)
		(fp_line
			(start 0 0.381)
			(end 0 -0.381)
			(stroke
				(width 0.1524)
				(type default)
			)
			(layer "F.SilkS")
		)
		(fp_line
			(start -0.7874 0.4064)
			(end -0.7874 -0.4064)
			(stroke
				(width 0.1524)
				(type default)
			)
			(layer "F.SilkS")
		)
		(fp_line
			(start -0.7874 -0.4064)
			(end 0.7874 -0.4064)
			(stroke
				(width 0.1524)
				(type default)
			)
			(layer "F.SilkS")
		)
		(fp_poly
			(pts
				(xy -0.5334 0.254) (xy -0.635 0.254) (xy -0.635 0.2286) (xy -0.635 -0.254) (xy -0.5334 -0.254) (xy -0.5334 -0.2794)
				(xy 0.5334 -0.2794) (xy 0.5334 -0.254) (xy 0.635 -0.254) (xy 0.635 0.254) (xy 0.5334 0.254) (xy 0.5334 0.2794)
				(xy -0.508 0.2794) (xy -0.5334 0.2794)
			)
			(stroke
				(width 0)
				(type default)
			)
			(fill no)
			(layer "F.CrtYd")
		)
		(pad "1" smd rect
			(at 0.40005 0 180)
			(size 0.4572 0.508)
			(layers "F.Cu" "F.Mask" "F.Paste")
			(net "P1V538_BMC_NODE1")
		)
		(pad "2" smd rect
			(at -0.40005 0 180)
			(size 0.4572 0.508)
			(layers "F.Cu" "F.Mask" "F.Paste")
			(net "GND")
		)
	)
	(footprint ""
		(layer "F.Cu")
		(at 169.728896 -40.663114)
		(property "Reference" "R267"
			(at -1.178814 -2.168398 0)
			(unlocked yes)
			(layer "F.SilkS")
			(effects
				(font
					(size 0.7874 0.5842)
					(thickness 0.1524)
				)
				(justify left)
			)
		)
		(property "Value" ""
			(at 0 0 0)
			(layer "F.Fab")
			(effects
				(font
					(size 1.27 1.27)
				)
			)
		)
		(duplicate_pad_numbers_are_jumpers no)
		(fp_line
			(start -0.7874 -0.4064)
			(end 0.7874 -0.4064)
			(stroke
				(width 0.1524)
				(type default)
			)
			(layer "F.SilkS")
		)
		(fp_line
			(start -0.7874 0.4064)
			(end -0.7874 -0.4064)
			(stroke
				(width 0.1524)
				(type default)
			)
			(layer "F.SilkS")
		)
		(fp_line
			(start 0.7874 -0.4064)
			(end 0.7874 0.4064)
			(stroke
				(width 0.1524)
				(type default)
			)
			(layer "F.SilkS")
		)
		(fp_line
			(start 0.7874 0.4064)
			(end -0.7874 0.4064)
			(stroke
				(width 0.1524)
				(type default)
			)
			(layer "F.SilkS")
		)
		(fp_poly
			(pts
				(xy -0.508 0.2794) (xy -0.508 0.2286) (xy -0.635 0.2286) (xy -0.635 -0.254) (xy -0.5334 -0.254)
				(xy -0.5334 -0.2794) (xy 0.5334 -0.2794) (xy 0.5334 -0.254) (xy 0.635 -0.254) (xy 0.635 0.254) (xy 0.5334 0.254)
				(xy 0.5334 0.2794)
			)
			(stroke
				(width 0)
				(type default)
			)
			(fill no)
			(layer "F.CrtYd")
		)
		(pad "1" smd rect
			(at 0.40005 0)
			(size 0.4572 0.508)
			(layers "F.Cu" "F.Mask" "F.Paste")
			(net "USB1_L_DN")
		)
		(pad "2" smd rect
			(at -0.40005 0)
			(size 0.4572 0.508)
			(layers "F.Cu" "F.Mask" "F.Paste")
			(net "USB1_DN")
		)
	)
	(footprint ""
		(layer "F.Cu")
		(at 159.652462 -75.31735 180)
		(property "Reference" "PR10"
			(at 3.90271 2.927096 0)
			(unlocked yes)
			(layer "F.SilkS")
			(effects
				(font
					(size 0.7874 0.5842)
					(thickness 0.1524)
				)
				(justify left)
			)
		)
		(property "Value" ""
			(at 0 0 180)
			(layer "F.Fab")
			(effects
				(font
					(size 1.27 1.27)
				)
			)
		)
		(duplicate_pad_numbers_are_jumpers no)
		(fp_line
			(start 0.7874 0.4064)
			(end -0.7874 0.4064)
			(stroke
				(width 0.1524)
				(type default)
			)
			(layer "F.SilkS")
		)
		(fp_line
			(start 0.7874 -0.4064)
			(end 0.7874 0.4064)
			(stroke
				(width 0.1524)
				(type default)
			)
			(layer "F.SilkS")
		)
		(fp_line
			(start -0.7874 0.4064)
			(end -0.7874 -0.4064)
			(stroke
				(width 0.1524)
				(type default)
			)
			(layer "F.SilkS")
		)
		(fp_line
			(start -0.7874 -0.4064)
			(end 0.7874 -0.4064)
			(stroke
				(width 0.1524)
				(type default)
			)
			(layer "F.SilkS")
		)
		(fp_poly
			(pts
				(xy -0.508 0.2794) (xy -0.508 0.2286) (xy -0.635 0.2286) (xy -0.635 -0.254) (xy -0.5334 -0.254)
				(xy -0.5334 -0.2794) (xy 0.5334 -0.2794) (xy 0.5334 -0.254) (xy 0.635 -0.254) (xy 0.635 0.254) (xy 0.5334 0.254)
				(xy 0.5334 0.2794)
			)
			(stroke
				(width 0)
				(type default)
			)
			(fill no)
			(layer "F.CrtYd")
		)
		(pad "1" smd rect
			(at 0.40005 0 180)
			(size 0.4572 0.508)
			(layers "F.Cu" "F.Mask" "F.Paste")
			(net "GND")
		)
		(pad "2" smd rect
			(at -0.40005 0 180)
			(size 0.4572 0.508)
			(layers "F.Cu" "F.Mask" "F.Paste")
			(net "P1V0_ADJ")
		)
	)
	(footprint ""
		(layer "F.Cu")
		(at 156.19476 -188.126624 90)
		(property "Reference" "R1221"
			(at 5.519674 -3.433826 90)
			(unlocked yes)
			(layer "F.SilkS")
			(effects
				(font
					(size 0.7874 0.5842)
					(thickness 0.1524)
				)
				(justify left)
			)
		)
		(property "Value" ""
			(at 0 0 90)
			(layer "F.Fab")
			(effects
				(font
					(size 1.27 1.27)
				)
			)
		)
		(duplicate_pad_numbers_are_jumpers no)
		(fp_line
			(start 0.7874 -0.4064)
			(end 0.7874 0.4064)
			(stroke
				(width 0.1524)
				(type default)
			)
			(layer "F.SilkS")
		)
		(fp_line
			(start -0.7874 -0.4064)
			(end 0.7874 -0.4064)
			(stroke
				(width 0.1524)
				(type default)
			)
			(layer "F.SilkS")
		)
		(fp_line
			(start 0.7874 0.4064)
			(end -0.7874 0.4064)
			(stroke
				(width 0.1524)
				(type default)
			)
			(layer "F.SilkS")
		)
		(fp_line
			(start -0.7874 0.4064)
			(end -0.7874 -0.4064)
			(stroke
				(width 0.1524)
				(type default)
			)
			(layer "F.SilkS")
		)
		(fp_poly
			(pts
				(xy -0.508 0.2794) (xy -0.508 0.2286) (xy -0.635 0.2286) (xy -0.635 -0.254) (xy -0.5334 -0.254)
				(xy -0.5334 -0.2794) (xy 0.5334 -0.2794) (xy 0.5334 -0.254) (xy 0.635 -0.254) (xy 0.635 0.254) (xy 0.5334 0.254)
				(xy 0.5334 0.2794)
			)
			(stroke
				(width 0)
				(type default)
			)
			(fill no)
			(layer "F.CrtYd")
		)
		(pad "1" smd rect
			(at 0.40005 0 90)
			(size 0.4572 0.508)
			(layers "F.Cu" "F.Mask" "F.Paste")
			(net "FAN3_TACH_R")
		)
		(pad "2" smd rect
			(at -0.40005 0 90)
			(size 0.4572 0.508)
			(layers "F.Cu" "F.Mask" "F.Paste")
			(net "GND")
		)
	)
	(footprint ""
		(layer "F.Cu")
		(at 115.30076 -179.363624 -90)
		(property "Reference" "D22"
			(at -3.11785 -7.56412 90)
			(unlocked yes)
			(layer "F.SilkS")
			(effects
				(font
					(size 0.635 0.4064)
					(thickness 0.1524)
				)
				(justify left)
			)
		)
		(property "Value" ""
			(at 0 0 270)
			(layer "F.Fab")
			(effects
				(font
					(size 1.27 1.27)
				)
			)
		)
		(duplicate_pad_numbers_are_jumpers no)
		(fp_line
			(start -1.3208 0.5588)
			(end -1.3208 -0.5588)
			(stroke
				(width 0.1524)
				(type default)
			)
			(layer "F.SilkS")
		)
		(fp_line
			(start 1.3208 0.5588)
			(end -1.3208 0.5588)
			(stroke
				(width 0.1524)
				(type default)
			)
			(layer "F.SilkS")
		)
		(fp_line
			(start 1.6256 0.5588)
			(end 1.6256 -0.5588)
			(stroke
				(width 0.1524)
				(type default)
			)
			(layer "F.SilkS")
		)
		(fp_line
			(start 1.778 0.5588)
			(end 1.3208 0.5588)
			(stroke
				(width 0.1524)
				(type default)
			)
			(layer "F.SilkS")
		)
		(fp_line
			(start -1.3208 -0.5588)
			(end 1.3208 -0.5588)
			(stroke
				(width 0.1524)
				(type default)
			)
			(layer "F.SilkS")
		)
		(fp_line
			(start 1.3208 -0.5588)
			(end 1.3208 0.5588)
			(stroke
				(width 0.1524)
				(type default)
			)
			(layer "F.SilkS")
		)
		(fp_line
			(start 1.4732 -0.5588)
			(end 1.4732 0.5588)
			(stroke
				(width 0.1524)
				(type default)
			)
			(layer "F.SilkS")
		)
		(fp_line
			(start 1.778 -0.5588)
			(end 1.778 0.5588)
			(stroke
				(width 0.1524)
				(type default)
			)
			(layer "F.SilkS")
		)
		(fp_line
			(start 1.778 -0.5588)
			(end 1.3208 -0.5588)
			(stroke
				(width 0.1524)
				(type default)
			)
			(layer "F.SilkS")
		)
		(fp_rect
			(start -1.1684 0.508)
			(end 1.1684 -0.508)
			(stroke
				(width 0)
				(type default)
			)
			(fill no)
			(layer "F.CrtYd")
		)
		(pad "A" smd rect
			(at -0.750062 0 270)
			(size 0.8128 0.8128)
			(layers "F.Cu" "F.Mask" "F.Paste")
			(net "UART_SW_S4_N")
		)
		(pad "C" smd rect
			(at 0.750062 0 270)
			(size 0.8128 0.8128)
			(layers "F.Cu" "F.Mask" "F.Paste")
			(net "N31341801")
		)
	)
)
